(kicad_pcb
	(version 20260206)
	(generator "pcbnew")
	(generator_version "10.0")
	(general
		(thickness 1.6)
		(legacy_teardrops no)
	)
	(paper "A4")
	(title_block
		(title "panther-plus-userver — 13130-1b_20150205.brd")
		(comment 1 "Honey Badger (Wiwynn) / footprint 406 of 1509 (DIMM2), pads 51-57 of 210")
	)
	(layers
		(0 "F.Cu" signal "TOP")
		(4 "In1.Cu" signal "L2")
		(6 "In2.Cu" signal "L3")
		(8 "In3.Cu" signal "L4")
		(10 "In4.Cu" signal "L5")
		(12 "In5.Cu" signal "L6")
		(14 "In6.Cu" signal "L7")
		(16 "In7.Cu" signal "L8")
		(18 "In8.Cu" signal "L9")
		(20 "In9.Cu" signal "L10")
		(22 "In10.Cu" signal "L11")
		(2 "B.Cu" signal "BOTTOM")
		(9 "F.Adhes" user "F.Adhesive")
		(11 "B.Adhes" user "B.Adhesive")
		(13 "F.Paste" user "Package Geometry/Pastemask Top")
		(15 "B.Paste" user "Package Geometry/Pastemask Bottom")
		(5 "F.SilkS" user "Ref Des/Silkscreen Top")
		(7 "B.SilkS" user "Ref Des/Silkscreen Bottom")
		(1 "F.Mask" user "Board Geometry/Soldermask Top")
		(3 "B.Mask" user "Board Geometry/Soldermask Bottom")
		(17 "Dwgs.User" user "User.Drawings")
		(19 "Cmts.User" user "User.Comments")
		(21 "Eco1.User" user "User.Eco1")
		(23 "Eco2.User" user "User.Eco2")
		(25 "Edge.Cuts" user "Board Geometry/Outline")
		(27 "Margin" user)
		(31 "F.CrtYd" user "Package Geometry/Place Bound Top")
		(29 "B.CrtYd" user "Package Geometry/Place Bound Bottom")
		(35 "F.Fab" user "Ref Des/Assembly Top")
		(33 "B.Fab" user "Ref Des/Assembly Bottom")
	)
	(footprint ""
		(layer "F.Cu")
		(at 158.500064 -66.699892 180)
		(property "Reference" "DIMM2"
			(at 0 0 180)
			(layer "F.SilkS")
			(hide yes)
			(effects
				(font
					(size 1.27 1.27)
				)
			)
		)
		(property "Value" "DDR3-204P-174-COLAY-1-GP"
			(at -40.682164 -17.468088 180)
			(unlocked yes)
			(layer "F.Fab")
			(hide yes)
			(effects
				(font
					(size 1.016 1.016)
					(thickness 0.1524)
				)
			)
		)
		(property "Device Type" "AS0A626-H8SN-7H-COLAY-1"
			(at -40.682164 -18.992088 180)
			(unlocked yes)
			(layer "F.Fab")
			(hide yes)
			(effects
				(font
					(size 1.016 1.016)
					(thickness 0.1524)
				)
			)
		)
		(duplicate_pad_numbers_are_jumpers no)
		(pad "49" smd custom
			(at -17.249902 4.106672 180)
			(size 0.1143 0.1143)
			(layers "F.Cu" "F.Mask" "F.Paste")
			(net "M_A_DQ22")
			(options
				(clearance outline)
				(anchor circle)
			)
			(primitives
				(gr_poly
					(pts
						(xy 0 0.9017) (xy -0.03175 0.89916) (xy -0.0635 0.889) (xy -0.09144 0.87376) (xy -0.11684 0.85344)
						(xy -0.13716 0.82804) (xy -0.1524 0.8001) (xy -0.16256 0.76835) (xy -0.1651 0.7366) (xy -0.1651 -0.13462)
						(xy -0.17272 -0.14224) (xy -0.19812 -0.1778) (xy -0.2032 -0.18796) (xy -0.20701 -0.19685) (xy -0.21209 -0.20701)
						(xy -0.2159 -0.21717) (xy -0.21844 -0.22733) (xy -0.22225 -0.23876) (xy -0.22352 -0.24892) (xy -0.22606 -0.25908)
						(xy -0.22733 -0.27051) (xy -0.22733 -0.28067) (xy -0.2286 -0.2921) (xy -0.22733 -0.30353) (xy -0.22733 -0.31369)
						(xy -0.22606 -0.32512) (xy -0.22352 -0.33528) (xy -0.22225 -0.34544) (xy -0.21844 -0.35687) (xy -0.2159 -0.36703)
						(xy -0.21209 -0.37719) (xy -0.20701 -0.38735) (xy -0.2032 -0.39624) (xy -0.19812 -0.4064) (xy -0.17272 -0.44196)
						(xy -0.1651 -0.44958) (xy -0.1651 -0.7366) (xy -0.16256 -0.76835) (xy -0.1524 -0.8001) (xy -0.13716 -0.82804)
						(xy -0.11684 -0.85344) (xy -0.09144 -0.87376) (xy -0.0635 -0.889) (xy -0.03175 -0.89916) (xy 0 -0.9017)
						(xy 0.03175 -0.89916) (xy 0.0635 -0.889) (xy 0.09144 -0.87376) (xy 0.11684 -0.85344) (xy 0.13716 -0.82804)
						(xy 0.1524 -0.8001) (xy 0.16256 -0.76835) (xy 0.1651 -0.7366) (xy 0.1651 -0.44958) (xy 0.17272 -0.44196)
						(xy 0.19812 -0.4064) (xy 0.2032 -0.39624) (xy 0.20701 -0.38735) (xy 0.21209 -0.37719) (xy 0.2159 -0.36703)
						(xy 0.21844 -0.35687) (xy 0.22225 -0.34544) (xy 0.22352 -0.33528) (xy 0.22606 -0.32512) (xy 0.22733 -0.31369)
						(xy 0.22733 -0.30353) (xy 0.2286 -0.2921) (xy 0.22733 -0.28067) (xy 0.22733 -0.27051) (xy 0.22606 -0.25908)
						(xy 0.22352 -0.24892) (xy 0.22225 -0.23876) (xy 0.21844 -0.22733) (xy 0.2159 -0.21717) (xy 0.21209 -0.20701)
						(xy 0.20701 -0.19685) (xy 0.2032 -0.18796) (xy 0.19812 -0.1778) (xy 0.17272 -0.14224) (xy 0.1651 -0.13462)
						(xy 0.1651 0.7366) (xy 0.16256 0.76835) (xy 0.1524 0.8001) (xy 0.13716 0.82804) (xy 0.11684 0.85344)
						(xy 0.09144 0.87376) (xy 0.0635 0.889) (xy 0.03175 0.89916)
					)
					(width 0)
					(fill yes)
				)
			)
		)
		(pad "50" smd custom
			(at -16.949928 -4.106672 180)
			(size 0.1143 0.1143)
			(layers "F.Cu" "F.Mask" "F.Paste")
			(net "M_A_DQ19")
			(options
				(clearance outline)
				(anchor circle)
			)
			(primitives
				(gr_poly
					(pts
						(xy 0 0.9017) (xy -0.03175 0.89916) (xy -0.0635 0.889) (xy -0.09144 0.87376) (xy -0.11684 0.85344)
						(xy -0.13716 0.82804) (xy -0.1524 0.8001) (xy -0.16256 0.76835) (xy -0.1651 0.7366) (xy -0.1651 0.44958)
						(xy -0.17272 0.44196) (xy -0.19812 0.4064) (xy -0.2032 0.39624) (xy -0.20701 0.38735) (xy -0.21209 0.37719)
						(xy -0.2159 0.36703) (xy -0.21844 0.35687) (xy -0.22225 0.34544) (xy -0.22352 0.33528) (xy -0.22606 0.32512)
						(xy -0.22733 0.31369) (xy -0.22733 0.30353) (xy -0.2286 0.2921) (xy -0.22733 0.28067) (xy -0.22733 0.27051)
						(xy -0.22606 0.25908) (xy -0.22352 0.24892) (xy -0.22225 0.23876) (xy -0.21844 0.22733) (xy -0.2159 0.21717)
						(xy -0.21209 0.20701) (xy -0.20701 0.19685) (xy -0.2032 0.18796) (xy -0.19812 0.1778) (xy -0.17272 0.14224)
						(xy -0.1651 0.13462) (xy -0.1651 -0.7366) (xy -0.16256 -0.76835) (xy -0.1524 -0.8001) (xy -0.13716 -0.82804)
						(xy -0.11684 -0.85344) (xy -0.09144 -0.87376) (xy -0.0635 -0.889) (xy -0.03175 -0.89916) (xy 0 -0.9017)
						(xy 0.03175 -0.89916) (xy 0.0635 -0.889) (xy 0.09144 -0.87376) (xy 0.11684 -0.85344) (xy 0.13716 -0.82804)
						(xy 0.1524 -0.8001) (xy 0.16256 -0.76835) (xy 0.1651 -0.7366) (xy 0.1651 0.13462) (xy 0.17272 0.14224)
						(xy 0.19812 0.1778) (xy 0.2032 0.18796) (xy 0.20701 0.19685) (xy 0.21209 0.20701) (xy 0.2159 0.21717)
						(xy 0.21844 0.22733) (xy 0.22225 0.23876) (xy 0.22352 0.24892) (xy 0.22606 0.25908) (xy 0.22733 0.27051)
						(xy 0.22733 0.28067) (xy 0.2286 0.2921) (xy 0.22733 0.30353) (xy 0.22733 0.31369) (xy 0.22606 0.32512)
						(xy 0.22352 0.33528) (xy 0.22225 0.34544) (xy 0.21844 0.35687) (xy 0.2159 0.36703) (xy 0.21209 0.37719)
						(xy 0.20701 0.38735) (xy 0.2032 0.39624) (xy 0.19812 0.4064) (xy 0.17272 0.44196) (xy 0.1651 0.44958)
						(xy 0.1651 0.7366) (xy 0.16256 0.76835) (xy 0.1524 0.8001) (xy 0.13716 0.82804) (xy 0.11684 0.85344)
						(xy 0.09144 0.87376) (xy 0.0635 0.889) (xy 0.03175 0.89916)
					)
					(width 0)
					(fill yes)
				)
			)
		)
		(pad "51" smd custom
			(at -16.649954 4.106672 180)
			(size 0.1143 0.1143)
			(layers "F.Cu" "F.Mask" "F.Paste")
			(net "M_A_DQ23")
			(options
				(clearance outline)
				(anchor circle)
			)
			(primitives
				(gr_poly
					(pts
						(xy 0 0.9017) (xy -0.03175 0.89916) (xy -0.0635 0.889) (xy -0.09144 0.87376) (xy -0.11684 0.85344)
						(xy -0.13716 0.82804) (xy -0.1524 0.8001) (xy -0.16256 0.76835) (xy -0.1651 0.7366) (xy -0.1651 0.11938)
						(xy -0.17272 0.11176) (xy -0.19812 0.0762) (xy -0.2032 0.06604) (xy -0.20701 0.05715) (xy -0.21209 0.04699)
						(xy -0.2159 0.03683) (xy -0.21844 0.02667) (xy -0.22225 0.01524) (xy -0.22352 0.00508) (xy -0.22606 -0.00508)
						(xy -0.22733 -0.01651) (xy -0.22733 -0.02667) (xy -0.2286 -0.0381) (xy -0.22733 -0.04953) (xy -0.22733 -0.05969)
						(xy -0.22606 -0.07112) (xy -0.22352 -0.08128) (xy -0.22225 -0.09144) (xy -0.21844 -0.10287) (xy -0.2159 -0.11303)
						(xy -0.21209 -0.12319) (xy -0.20701 -0.13335) (xy -0.2032 -0.14224) (xy -0.19812 -0.1524) (xy -0.17272 -0.18796)
						(xy -0.1651 -0.19558) (xy -0.1651 -0.7366) (xy -0.16256 -0.76835) (xy -0.1524 -0.8001) (xy -0.13716 -0.82804)
						(xy -0.11684 -0.85344) (xy -0.09144 -0.87376) (xy -0.0635 -0.889) (xy -0.03175 -0.89916) (xy 0 -0.9017)
						(xy 0.03175 -0.89916) (xy 0.0635 -0.889) (xy 0.09144 -0.87376) (xy 0.11684 -0.85344) (xy 0.13716 -0.82804)
						(xy 0.1524 -0.8001) (xy 0.16256 -0.76835) (xy 0.1651 -0.7366) (xy 0.1651 -0.19685) (xy 0.17272 -0.18923)
						(xy 0.17907 -0.18034) (xy 0.18669 -0.17145) (xy 0.19177 -0.16256) (xy 0.19812 -0.15367) (xy 0.20828 -0.13335)
						(xy 0.21971 -0.10287) (xy 0.22225 -0.09271) (xy 0.22479 -0.08128) (xy 0.22606 -0.07112) (xy 0.2286 -0.05969)
						(xy 0.2286 -0.01651) (xy 0.22606 -0.00508) (xy 0.22479 0.00508) (xy 0.22225 0.01651) (xy 0.21971 0.02667)
						(xy 0.20828 0.05715) (xy 0.19812 0.07747) (xy 0.19177 0.08636) (xy 0.18669 0.09525) (xy 0.17907 0.10414)
						(xy 0.17272 0.11303) (xy 0.1651 0.12065) (xy 0.1651 0.7366) (xy 0.16256 0.76835) (xy 0.1524 0.8001)
						(xy 0.13716 0.82804) (xy 0.11684 0.85344) (xy 0.09144 0.87376) (xy 0.0635 0.889) (xy 0.03175 0.89916)
					)
					(width 0)
					(fill yes)
				)
			)
		)
		(pad "52" smd custom
			(at -16.34998 -4.106672 180)
			(size 0.1143 0.1143)
			(layers "F.Cu" "F.Mask" "F.Paste")
			(net "GND")
			(options
				(clearance outline)
				(anchor circle)
			)
			(primitives
				(gr_poly
					(pts
						(xy 0 0.9017) (xy -0.03175 0.89916) (xy -0.0635 0.889) (xy -0.09144 0.87376) (xy -0.11684 0.85344)
						(xy -0.13716 0.82804) (xy -0.1524 0.8001) (xy -0.16256 0.76835) (xy -0.1651 0.7366) (xy -0.1651 0.19685)
						(xy -0.17272 0.18923) (xy -0.17907 0.18034) (xy -0.18669 0.17145) (xy -0.19177 0.16256) (xy -0.19812 0.15367)
						(xy -0.20828 0.13335) (xy -0.21971 0.10287) (xy -0.22225 0.09271) (xy -0.22479 0.08128) (xy -0.22606 0.07112)
						(xy -0.2286 0.05969) (xy -0.2286 0.01651) (xy -0.22606 0.00508) (xy -0.22479 -0.00508) (xy -0.22225 -0.01651)
						(xy -0.21971 -0.02667) (xy -0.20828 -0.05715) (xy -0.19812 -0.07747) (xy -0.19177 -0.08636) (xy -0.18669 -0.09525)
						(xy -0.17907 -0.10414) (xy -0.17272 -0.11303) (xy -0.1651 -0.12065) (xy -0.1651 -0.7366) (xy -0.16256 -0.76835)
						(xy -0.1524 -0.8001) (xy -0.13716 -0.82804) (xy -0.11684 -0.85344) (xy -0.09144 -0.87376) (xy -0.0635 -0.889)
						(xy -0.03175 -0.89916) (xy 0 -0.9017) (xy 0.03175 -0.89916) (xy 0.0635 -0.889) (xy 0.09144 -0.87376)
						(xy 0.11684 -0.85344) (xy 0.13716 -0.82804) (xy 0.1524 -0.8001) (xy 0.16256 -0.76835) (xy 0.1651 -0.7366)
						(xy 0.1651 -0.11938) (xy 0.17272 -0.11176) (xy 0.19812 -0.0762) (xy 0.2032 -0.06604) (xy 0.20701 -0.05715)
						(xy 0.21209 -0.04699) (xy 0.2159 -0.03683) (xy 0.21844 -0.02667) (xy 0.22225 -0.01524) (xy 0.22352 -0.00508)
						(xy 0.22606 0.00508) (xy 0.22733 0.01651) (xy 0.22733 0.02667) (xy 0.2286 0.0381) (xy 0.22733 0.04953)
						(xy 0.22733 0.05969) (xy 0.22606 0.07112) (xy 0.22352 0.08128) (xy 0.22225 0.09144) (xy 0.21844 0.10287)
						(xy 0.2159 0.11303) (xy 0.21209 0.12319) (xy 0.20701 0.13335) (xy 0.2032 0.14224) (xy 0.19812 0.1524)
						(xy 0.17272 0.18796) (xy 0.1651 0.19558) (xy 0.1651 0.7366) (xy 0.16256 0.76835) (xy 0.1524 0.8001)
						(xy 0.13716 0.82804) (xy 0.11684 0.85344) (xy 0.09144 0.87376) (xy 0.0635 0.889) (xy 0.03175 0.89916)
					)
					(width 0)
					(fill yes)
				)
			)
		)
		(pad "53" smd custom
			(at -16.050006 4.106672 180)
			(size 0.1143 0.1143)
			(layers "F.Cu" "F.Mask" "F.Paste")
			(net "GND")
			(options
				(clearance outline)
				(anchor circle)
			)
			(primitives
				(gr_poly
					(pts
						(xy 0 0.9017) (xy -0.03175 0.89916) (xy -0.0635 0.889) (xy -0.09144 0.87376) (xy -0.11684 0.85344)
						(xy -0.13716 0.82804) (xy -0.1524 0.8001) (xy -0.16256 0.76835) (xy -0.1651 0.7366) (xy -0.1651 -0.13462)
						(xy -0.17272 -0.14224) (xy -0.19812 -0.1778) (xy -0.2032 -0.18796) (xy -0.20701 -0.19685) (xy -0.21209 -0.20701)
						(xy -0.2159 -0.21717) (xy -0.21844 -0.22733) (xy -0.22225 -0.23876) (xy -0.22352 -0.24892) (xy -0.22606 -0.25908)
						(xy -0.22733 -0.27051) (xy -0.22733 -0.28067) (xy -0.2286 -0.2921) (xy -0.22733 -0.30353) (xy -0.22733 -0.31369)
						(xy -0.22606 -0.32512) (xy -0.22352 -0.33528) (xy -0.22225 -0.34544) (xy -0.21844 -0.35687) (xy -0.2159 -0.36703)
						(xy -0.21209 -0.37719) (xy -0.20701 -0.38735) (xy -0.2032 -0.39624) (xy -0.19812 -0.4064) (xy -0.17272 -0.44196)
						(xy -0.1651 -0.44958) (xy -0.1651 -0.7366) (xy -0.16256 -0.76835) (xy -0.1524 -0.8001) (xy -0.13716 -0.82804)
						(xy -0.11684 -0.85344) (xy -0.09144 -0.87376) (xy -0.0635 -0.889) (xy -0.03175 -0.89916) (xy 0 -0.9017)
						(xy 0.03175 -0.89916) (xy 0.0635 -0.889) (xy 0.09144 -0.87376) (xy 0.11684 -0.85344) (xy 0.13716 -0.82804)
						(xy 0.1524 -0.8001) (xy 0.16256 -0.76835) (xy 0.1651 -0.7366) (xy 0.1651 -0.44958) (xy 0.17272 -0.44196)
						(xy 0.19812 -0.4064) (xy 0.2032 -0.39624) (xy 0.20701 -0.38735) (xy 0.21209 -0.37719) (xy 0.2159 -0.36703)
						(xy 0.21844 -0.35687) (xy 0.22225 -0.34544) (xy 0.22352 -0.33528) (xy 0.22606 -0.32512) (xy 0.22733 -0.31369)
						(xy 0.22733 -0.30353) (xy 0.2286 -0.2921) (xy 0.22733 -0.28067) (xy 0.22733 -0.27051) (xy 0.22606 -0.25908)
						(xy 0.22352 -0.24892) (xy 0.22225 -0.23876) (xy 0.21844 -0.22733) (xy 0.2159 -0.21717) (xy 0.21209 -0.20701)
						(xy 0.20701 -0.19685) (xy 0.2032 -0.18796) (xy 0.19812 -0.1778) (xy 0.17272 -0.14224) (xy 0.1651 -0.13462)
						(xy 0.1651 0.7366) (xy 0.16256 0.76835) (xy 0.1524 0.8001) (xy 0.13716 0.82804) (xy 0.11684 0.85344)
						(xy 0.09144 0.87376) (xy 0.0635 0.889) (xy 0.03175 0.89916)
					)
					(width 0)
					(fill yes)
				)
			)
		)
		(pad "54" smd custom
			(at -15.750032 -4.106672 180)
			(size 0.1143 0.1143)
			(layers "F.Cu" "F.Mask" "F.Paste")
			(net "M_A_DQ24")
			(options
				(clearance outline)
				(anchor circle)
			)
			(primitives
				(gr_poly
					(pts
						(xy 0 0.9017) (xy -0.03175 0.89916) (xy -0.0635 0.889) (xy -0.09144 0.87376) (xy -0.11684 0.85344)
						(xy -0.13716 0.82804) (xy -0.1524 0.8001) (xy -0.16256 0.76835) (xy -0.1651 0.7366) (xy -0.1651 0.44958)
						(xy -0.17272 0.44196) (xy -0.19812 0.4064) (xy -0.2032 0.39624) (xy -0.20701 0.38735) (xy -0.21209 0.37719)
						(xy -0.2159 0.36703) (xy -0.21844 0.35687) (xy -0.22225 0.34544) (xy -0.22352 0.33528) (xy -0.22606 0.32512)
						(xy -0.22733 0.31369) (xy -0.22733 0.30353) (xy -0.2286 0.2921) (xy -0.22733 0.28067) (xy -0.22733 0.27051)
						(xy -0.22606 0.25908) (xy -0.22352 0.24892) (xy -0.22225 0.23876) (xy -0.21844 0.22733) (xy -0.2159 0.21717)
						(xy -0.21209 0.20701) (xy -0.20701 0.19685) (xy -0.2032 0.18796) (xy -0.19812 0.1778) (xy -0.17272 0.14224)
						(xy -0.1651 0.13462) (xy -0.1651 -0.7366) (xy -0.16256 -0.76835) (xy -0.1524 -0.8001) (xy -0.13716 -0.82804)
						(xy -0.11684 -0.85344) (xy -0.09144 -0.87376) (xy -0.0635 -0.889) (xy -0.03175 -0.89916) (xy 0 -0.9017)
						(xy 0.03175 -0.89916) (xy 0.0635 -0.889) (xy 0.09144 -0.87376) (xy 0.11684 -0.85344) (xy 0.13716 -0.82804)
						(xy 0.1524 -0.8001) (xy 0.16256 -0.76835) (xy 0.1651 -0.7366) (xy 0.1651 0.13462) (xy 0.17272 0.14224)
						(xy 0.19812 0.1778) (xy 0.2032 0.18796) (xy 0.20701 0.19685) (xy 0.21209 0.20701) (xy 0.2159 0.21717)
						(xy 0.21844 0.22733) (xy 0.22225 0.23876) (xy 0.22352 0.24892) (xy 0.22606 0.25908) (xy 0.22733 0.27051)
						(xy 0.22733 0.28067) (xy 0.2286 0.2921) (xy 0.22733 0.30353) (xy 0.22733 0.31369) (xy 0.22606 0.32512)
						(xy 0.22352 0.33528) (xy 0.22225 0.34544) (xy 0.21844 0.35687) (xy 0.2159 0.36703) (xy 0.21209 0.37719)
						(xy 0.20701 0.38735) (xy 0.2032 0.39624) (xy 0.19812 0.4064) (xy 0.17272 0.44196) (xy 0.1651 0.44958)
						(xy 0.1651 0.7366) (xy 0.16256 0.76835) (xy 0.1524 0.8001) (xy 0.13716 0.82804) (xy 0.11684 0.85344)
						(xy 0.09144 0.87376) (xy 0.0635 0.889) (xy 0.03175 0.89916)
					)
					(width 0)
					(fill yes)
				)
			)
		)
		(pad "55" smd custom
			(at -15.450058 4.106672 180)
			(size 0.1143 0.1143)
			(layers "F.Cu" "F.Mask" "F.Paste")
			(net "M_A_DQ28")
			(options
				(clearance outline)
				(anchor circle)
			)
			(primitives
				(gr_poly
					(pts
						(xy 0 0.9017) (xy -0.03175 0.89916) (xy -0.0635 0.889) (xy -0.09144 0.87376) (xy -0.11684 0.85344)
						(xy -0.13716 0.82804) (xy -0.1524 0.8001) (xy -0.16256 0.76835) (xy -0.1651 0.7366) (xy -0.1651 0.11938)
						(xy -0.17272 0.11176) (xy -0.19812 0.0762) (xy -0.2032 0.06604) (xy -0.20701 0.05715) (xy -0.21209 0.04699)
						(xy -0.2159 0.03683) (xy -0.21844 0.02667) (xy -0.22225 0.01524) (xy -0.22352 0.00508) (xy -0.22606 -0.00508)
						(xy -0.22733 -0.01651) (xy -0.22733 -0.02667) (xy -0.2286 -0.0381) (xy -0.22733 -0.04953) (xy -0.22733 -0.05969)
						(xy -0.22606 -0.07112) (xy -0.22352 -0.08128) (xy -0.22225 -0.09144) (xy -0.21844 -0.10287) (xy -0.2159 -0.11303)
						(xy -0.21209 -0.12319) (xy -0.20701 -0.13335) (xy -0.2032 -0.14224) (xy -0.19812 -0.1524) (xy -0.17272 -0.18796)
						(xy -0.1651 -0.19558) (xy -0.1651 -0.7366) (xy -0.16256 -0.76835) (xy -0.1524 -0.8001) (xy -0.13716 -0.82804)
						(xy -0.11684 -0.85344) (xy -0.09144 -0.87376) (xy -0.0635 -0.889) (xy -0.03175 -0.89916) (xy 0 -0.9017)
						(xy 0.03175 -0.89916) (xy 0.0635 -0.889) (xy 0.09144 -0.87376) (xy 0.11684 -0.85344) (xy 0.13716 -0.82804)
						(xy 0.1524 -0.8001) (xy 0.16256 -0.76835) (xy 0.1651 -0.7366) (xy 0.1651 -0.19685) (xy 0.17272 -0.18923)
						(xy 0.17907 -0.18034) (xy 0.18669 -0.17145) (xy 0.19177 -0.16256) (xy 0.19812 -0.15367) (xy 0.20828 -0.13335)
						(xy 0.21971 -0.10287) (xy 0.22225 -0.09271) (xy 0.22479 -0.08128) (xy 0.22606 -0.07112) (xy 0.2286 -0.05969)
						(xy 0.2286 -0.01651) (xy 0.22606 -0.00508) (xy 0.22479 0.00508) (xy 0.22225 0.01651) (xy 0.21971 0.02667)
						(xy 0.20828 0.05715) (xy 0.19812 0.07747) (xy 0.19177 0.08636) (xy 0.18669 0.09525) (xy 0.17907 0.10414)
						(xy 0.17272 0.11303) (xy 0.1651 0.12065) (xy 0.1651 0.7366) (xy 0.16256 0.76835) (xy 0.1524 0.8001)
						(xy 0.13716 0.82804) (xy 0.11684 0.85344) (xy 0.09144 0.87376) (xy 0.0635 0.889) (xy 0.03175 0.89916)
					)
					(width 0)
					(fill yes)
				)
			)
		)
	)
)
